# BASEBOARD_FAB2 (Tioga Pass) — schematic netlist excerpt (pin names and nets, part order shuffled) for the footprints in the layout excerpt that follows; sources: Cadence DE-HDL packaged netlist, KiCad conversion of Wiwynn_Tioga_Pass_MB.brd

C6P3  CAP_A  22.0UF 4V 20% X6S  pkg 0603V  page 203 : A = PVCCIN_CPU0 ; B = GND
R2T72  RES  150.0 1% CHIP  pkg 0402  page 93 : A = PVCCIO_CPU0 ; B = H_CPU0_PROCHOT_G_N
C3P17  CAP  0.22UF 16V 10% X7R  pkg 0402  page 107 : A = P3E_CPU0_PE1_SS_TXN<1> ; B = P3E_CPU0_PE1_PCH_TXN<1>

(kicad_pcb
	(version 20260206)
	(generator "pcbnew")
	(generator_version "10.0")
	(general
		(thickness 1.6)
		(legacy_teardrops no)
	)
	(paper "A4")
	(title_block
		(title "Wiwynn_Tioga_Pass_MB.brd")
		(comment 1 "Tioga Pass / footprints 2650-2652 of 4770")
	)
	(layers
		(0 "F.Cu" signal "TOP")
		(4 "In1.Cu" signal "L2GND")
		(6 "In2.Cu" signal "L3")
		(8 "In3.Cu" signal "L4GND")
		(10 "In4.Cu" signal "L5")
		(12 "In5.Cu" signal "L6GND")
		(14 "In6.Cu" signal "L7VCC")
		(16 "In7.Cu" signal "L8VCC")
		(18 "In8.Cu" signal "L9GND")
		(20 "In9.Cu" signal "L10")
		(22 "In10.Cu" signal "L11GND")
		(24 "In11.Cu" signal "L12")
		(26 "In12.Cu" signal "L13GND")
		(2 "B.Cu" signal "BOTTOM")
		(9 "F.Adhes" user "F.Adhesive")
		(11 "B.Adhes" user "B.Adhesive")
		(13 "F.Paste" user "Package Geometry/Pastemask Top")
		(15 "B.Paste" user "Package Geometry/Pastemask Bottom")
		(5 "F.SilkS" user "Ref Des/Silkscreen Top")
		(7 "B.SilkS" user "Ref Des/Silkscreen Bottom")
		(1 "F.Mask" user "Board Geometry/Soldermask Top")
		(3 "B.Mask" user "Board Geometry/Soldermask Bottom")
		(17 "Dwgs.User" user "User.Drawings")
		(19 "Cmts.User" user "User.Comments")
		(21 "Eco1.User" user "User.Eco1")
		(23 "Eco2.User" user "User.Eco2")
		(25 "Edge.Cuts" user "Board Geometry/Outline")
		(27 "Margin" user)
		(31 "F.CrtYd" user "Package Geometry/Place Bound Top")
		(29 "B.CrtYd" user "Package Geometry/Place Bound Bottom")
		(35 "F.Fab" user "Ref Des/Assembly Top")
		(33 "B.Fab" user "Ref Des/Assembly Bottom")
	)
	(footprint ""
		(layer "B.Cu")
		(at 214.503 -86.4235)
		(property "Reference" "C6P3"
			(at 0 0 0)
			(layer "B.SilkS")
			(hide yes)
			(effects
				(font
					(size 1.27 1.27)
				)
				(justify mirror)
			)
		)
		(property "Value" ""
			(at 0 0 0)
			(layer "B.Fab")
			(effects
				(font
					(size 1.27 1.27)
				)
				(justify mirror)
			)
		)
		(duplicate_pad_numbers_are_jumpers no)
		(fp_poly
			(pts
				(xy 0.4953 -0.2032) (xy -0.4953 -0.2032) (xy -0.4953 1.6002) (xy 0.4953 1.6002)
			)
			(stroke
				(width 0)
				(type default)
			)
			(fill no)
			(layer "B.CrtYd")
		)
		(fp_line
			(start -0.4953 -0.2032)
			(end -0.4953 1.6002)
			(stroke
				(width 0.1)
				(type default)
			)
			(layer "B.Fab")
		)
		(fp_line
			(start -0.4953 1.6002)
			(end 0.4953 1.6002)
			(stroke
				(width 0.1)
				(type default)
			)
			(layer "B.Fab")
		)
		(fp_line
			(start 0.4953 -0.2032)
			(end -0.4953 -0.2032)
			(stroke
				(width 0.1)
				(type default)
			)
			(layer "B.Fab")
		)
		(fp_line
			(start 0.4953 1.6002)
			(end 0.4953 -0.2032)
			(stroke
				(width 0.1)
				(type default)
			)
			(layer "B.Fab")
		)
		(pad "1" smd rect
			(at 0 0 180)
			(size 0.762 0.889)
			(layers "B.Cu" "B.Mask" "B.Paste")
			(net "PVCCIN_CPU0")
		)
		(pad "2" smd rect
			(at 0 1.397 180)
			(size 0.762 0.889)
			(layers "B.Cu" "B.Mask" "B.Paste")
			(net "GND")
		)
		(zone
			(layer "B.Cu")
			(hatch none 0.5)
			(connect_pads
				(clearance 0)
			)
			(min_thickness 0.25)
			(keepout
				(tracks not_allowed)
				(vias allowed)
				(pads allowed)
				(copperpour not_allowed)
				(footprints allowed)
			)
			(placement
				(enabled no)
				(sheetname "")
			)
			(fill
				(thermal_gap 0.5)
				(thermal_bridge_width 0.5)
				(island_removal_mode 0)
			)
			(polygon
				(pts
					(xy 214.884 -85.979) (xy 214.122 -85.979) (xy 214.122 -85.471) (xy 214.884 -85.471)
				)
			)
		)
	)
	(footprint ""
		(layer "B.Cu")
		(at 375.270268 -47.566326 -90)
		(property "Reference" "R2T72"
			(at 0 0 90)
			(layer "B.SilkS")
			(hide yes)
			(effects
				(font
					(size 1.27 1.27)
				)
				(justify mirror)
			)
		)
		(property "Value" ""
			(at 0 0 90)
			(layer "B.Fab")
			(effects
				(font
					(size 1.27 1.27)
				)
				(justify mirror)
			)
		)
		(duplicate_pad_numbers_are_jumpers no)
		(fp_poly
			(pts
				(xy 0.2794 -0.1016) (xy -0.2794 -0.1016) (xy -0.2794 0.9906) (xy 0.2794 0.9906)
			)
			(stroke
				(width 0)
				(type default)
			)
			(fill no)
			(layer "B.CrtYd")
		)
		(fp_line
			(start -0.2794 0.9906)
			(end -0.2794 -0.1016)
			(stroke
				(width 0.1)
				(type default)
			)
			(layer "B.Fab")
		)
		(fp_line
			(start 0.2794 0.9906)
			(end -0.2794 0.9906)
			(stroke
				(width 0.1)
				(type default)
			)
			(layer "B.Fab")
		)
		(fp_line
			(start -0.2794 -0.1016)
			(end 0.2794 -0.1016)
			(stroke
				(width 0.1)
				(type default)
			)
			(layer "B.Fab")
		)
		(fp_line
			(start 0.2794 -0.1016)
			(end 0.2794 0.9906)
			(stroke
				(width 0.1)
				(type default)
			)
			(layer "B.Fab")
		)
		(pad "1" smd rect
			(at 0 0 90)
			(size 0.508 0.508)
			(layers "B.Cu" "B.Mask" "B.Paste")
			(net "PVCCIO_CPU0")
		)
		(pad "2" smd rect
			(at 0 0.889 90)
			(size 0.508 0.508)
			(layers "B.Cu" "B.Mask" "B.Paste")
			(net "H_CPU0_PROCHOT_G_N")
		)
		(zone
			(layer "B.Cu")
			(hatch none 0.5)
			(connect_pads
				(clearance 0)
			)
			(min_thickness 0.25)
			(keepout
				(tracks not_allowed)
				(vias allowed)
				(pads allowed)
				(copperpour not_allowed)
				(footprints allowed)
			)
			(placement
				(enabled no)
				(sheetname "")
			)
			(fill
				(thermal_gap 0.5)
				(thermal_bridge_width 0.5)
				(island_removal_mode 0)
			)
			(polygon
				(pts
					(xy 374.635268 -47.312326) (xy 374.635268 -47.820326) (xy 375.016268 -47.820326) (xy 375.016268 -47.312326)
				)
			)
		)
		(zone
			(layer "B.Cu")
			(hatch none 0.5)
			(connect_pads
				(clearance 0)
			)
			(min_thickness 0.25)
			(keepout
				(tracks allowed)
				(vias not_allowed)
				(pads allowed)
				(copperpour not_allowed)
				(footprints allowed)
			)
			(placement
				(enabled no)
				(sheetname "")
			)
			(fill
				(thermal_gap 0.5)
				(thermal_bridge_width 0.5)
				(island_removal_mode 0)
			)
			(polygon
				(pts
					(xy 375.016268 -47.312326) (xy 375.016268 -47.820326) (xy 374.635268 -47.820326) (xy 374.635268 -47.312326)
				)
			)
		)
	)
	(footprint ""
		(layer "B.Cu")
		(at 343.063068 -77.694536 180)
		(property "Reference" "C3P17"
			(at 0 0 0)
			(layer "B.SilkS")
			(hide yes)
			(effects
				(font
					(size 1.27 1.27)
				)
				(justify mirror)
			)
		)
		(property "Value" ""
			(at 0 0 0)
			(layer "B.Fab")
			(effects
				(font
					(size 1.27 1.27)
				)
				(justify mirror)
			)
		)
		(duplicate_pad_numbers_are_jumpers no)
		(fp_poly
			(pts
				(xy -0.3048 -0.1016) (xy -0.3048 0.9906) (xy 0.3048 0.9906) (xy 0.3048 -0.1016)
			)
			(stroke
				(width 0)
				(type default)
			)
			(fill no)
			(layer "B.CrtYd")
		)
		(fp_line
			(start 0.3048 0.9906)
			(end -0.3048 0.9906)
			(stroke
				(width 0.1)
				(type default)
			)
			(layer "B.Fab")
		)
		(fp_line
			(start 0.3048 -0.1016)
			(end 0.3048 0.9906)
			(stroke
				(width 0.1)
				(type default)
			)
			(layer "B.Fab")
		)
		(fp_line
			(start -0.3048 0.9906)
			(end -0.3048 -0.1016)
			(stroke
				(width 0.1)
				(type default)
			)
			(layer "B.Fab")
		)
		(fp_line
			(start -0.3048 -0.1016)
			(end 0.3048 -0.1016)
			(stroke
				(width 0.1)
				(type default)
			)
			(layer "B.Fab")
		)
		(pad "1" smd rect
			(at 0 0)
			(size 0.508 0.508)
			(layers "B.Cu" "B.Mask" "B.Paste")
			(net "P3E_CPU0_PE1_SS_TXN<1>")
		)
		(pad "2" smd rect
			(at 0 0.889)
			(size 0.508 0.508)
			(layers "B.Cu" "B.Mask" "B.Paste")
			(net "P3E_CPU0_PE1_PCH_TXN<1>")
		)
		(zone
			(layer "B.Cu")
			(hatch none 0.5)
			(connect_pads
				(clearance 0)
			)
			(min_thickness 0.25)
			(keepout
				(tracks not_allowed)
				(vias allowed)
				(pads allowed)
				(copperpour not_allowed)
				(footprints allowed)
			)
			(placement
				(enabled no)
				(sheetname "")
			)
			(fill
				(thermal_gap 0.5)
				(thermal_bridge_width 0.5)
				(island_removal_mode 0)
			)
			(polygon
				(pts
					(xy 342.809068 -78.329536) (xy 343.317068 -78.329536) (xy 343.317068 -77.948536) (xy 342.809068 -77.948536)
				)
			)
		)
		(zone
			(layer "B.Cu")
			(hatch none 0.5)
			(connect_pads
				(clearance 0)
			)
			(min_thickness 0.25)
			(keepout
				(tracks allowed)
				(vias not_allowed)
				(pads allowed)
				(copperpour not_allowed)
				(footprints allowed)
			)
			(placement
				(enabled no)
				(sheetname "")
			)
			(fill
				(thermal_gap 0.5)
				(thermal_bridge_width 0.5)
				(island_removal_mode 0)
			)
			(polygon
				(pts
					(xy 342.809068 -77.948536) (xy 343.317068 -77.948536) (xy 343.317068 -78.329536) (xy 342.809068 -78.329536)
				)
			)
		)
	)
)
